(kicad_pcb
	(version 20260206)
	(generator "pcbnew")
	(generator_version "10.0")
	(general
		(thickness 1.6)
		(legacy_teardrops no)
	)
	(paper "A4")
	(title_block
		(title "03242023_DA0F0TMBIJ0_F0T_Motherboard_J_brd_V01_OCP.brd")
		(comment 1 "Grand Teton / footprint 1682 of 6105 (U1), pads 641-749 of 4677")
	)
	(layers
		(0 "F.Cu" signal "TOP")
		(4 "In1.Cu" signal "GND")
		(6 "In2.Cu" signal "IN1")
		(8 "In3.Cu" signal "GND1")
		(10 "In4.Cu" signal "IN2")
		(12 "In5.Cu" signal "GND2")
		(14 "In6.Cu" signal "IN3")
		(16 "In7.Cu" signal "GND3")
		(18 "In8.Cu" signal "VCC")
		(20 "In9.Cu" signal "VCC1")
		(22 "In10.Cu" signal "GND4")
		(24 "In11.Cu" signal "IN4")
		(26 "In12.Cu" signal "GND5")
		(28 "In13.Cu" signal "IN5")
		(30 "In14.Cu" signal "GND6")
		(32 "In15.Cu" signal "IN6")
		(34 "In16.Cu" signal "GND7")
		(2 "B.Cu" signal "BOTTOM")
		(9 "F.Adhes" user "F.Adhesive")
		(11 "B.Adhes" user "B.Adhesive")
		(13 "F.Paste" user "Package Geometry/Pastemask Top")
		(15 "B.Paste" user "Package Geometry/Pastemask Bottom")
		(5 "F.SilkS" user "Ref Des/Silkscreen Top")
		(7 "B.SilkS" user "Ref Des/Silkscreen Bottom")
		(1 "F.Mask" user "Board Geometry/Soldermask Top")
		(3 "B.Mask" user "Board Geometry/Soldermask Bottom")
		(17 "Dwgs.User" user "User.Drawings")
		(19 "Cmts.User" user "User.Comments")
		(21 "Eco1.User" user "User.Eco1")
		(23 "Eco2.User" user "User.Eco2")
		(25 "Edge.Cuts" user "Board Geometry/Outline")
		(27 "Margin" user)
		(31 "F.CrtYd" user "Package Geometry/Place Bound Top")
		(29 "B.CrtYd" user "Package Geometry/Place Bound Bottom")
		(35 "F.Fab" user "Ref Des/Assembly Top")
		(33 "B.Fab" user "Ref Des/Assembly Bottom")
	)
	(footprint ""
		(layer "F.Cu")
		(at 111.93018 -251.76988 90)
		(property "Reference" "U1"
			(at -74.913236 41.548812 0)
			(unlocked yes)
			(layer "F.SilkS")
			(effects
				(font
					(size 1.6002 1.1938)
					(thickness 0.1524)
				)
				(justify left)
			)
		)
		(property "Value" ""
			(at 0 0 90)
			(layer "F.Fab")
			(effects
				(font
					(size 1.27 1.27)
				)
			)
		)
		(duplicate_pad_numbers_are_jumpers no)
		(pad "AP61" smd circle
			(at 13.008356 -11.457686 270)
			(size 0.4318 0.4318)
			(layers "F.Cu" "F.Mask" "F.Paste")
			(net "GND")
		)
		(pad "AP63" smd circle
			(at 14.635988 -11.457686 270)
			(size 0.4318 0.4318)
			(layers "F.Cu" "F.Mask" "F.Paste")
			(net "M_D_CPU1_SA_DQ<30>")
		)
		(pad "AP65" smd circle
			(at 16.263874 -11.457686 270)
			(size 0.4318 0.4318)
			(layers "F.Cu" "F.Mask" "F.Paste")
			(net "M_D_CPU1_SA_DQ<27>")
		)
		(pad "AP67" smd circle
			(at 17.89176 -11.457686 270)
			(size 0.4318 0.4318)
			(layers "F.Cu" "F.Mask" "F.Paste")
			(net "GND")
		)
		(pad "AP69" smd circle
			(at 19.519392 -11.457686 270)
			(size 0.4318 0.4318)
			(layers "F.Cu" "F.Mask" "F.Paste")
			(net "M_D_CPU1_SA_DQ<22>")
		)
		(pad "AP71" smd circle
			(at 21.147278 -11.457686 270)
			(size 0.4318 0.4318)
			(layers "F.Cu" "F.Mask" "F.Paste")
			(net "M_D_CPU1_SA_DQ<19>")
		)
		(pad "AP73" smd circle
			(at 22.77491 -11.457686 270)
			(size 0.4318 0.4318)
			(layers "F.Cu" "F.Mask" "F.Paste")
			(net "GND")
		)
		(pad "AP75" smd circle
			(at 24.402796 -11.457686 270)
			(size 0.4318 0.4318)
			(layers "F.Cu" "F.Mask" "F.Paste")
			(net "M_D_CPU1_SA_DQ<14>")
		)
		(pad "AP77" smd circle
			(at 26.030682 -11.457686 270)
			(size 0.4318 0.4318)
			(layers "F.Cu" "F.Mask" "F.Paste")
			(net "M_D_CPU1_SA_DQ<11>")
		)
		(pad "AP79" smd circle
			(at 27.658314 -11.457686 270)
			(size 0.4318 0.4318)
			(layers "F.Cu" "F.Mask" "F.Paste")
			(net "GND")
		)
		(pad "AP81" smd circle
			(at 29.2862 -11.457686 270)
			(size 0.4318 0.4318)
			(layers "F.Cu" "F.Mask" "F.Paste")
			(net "UPI_CPU1_CPU0_P2P2_DP<12>")
		)
		(pad "AP83" smd circle
			(at 30.914086 -11.457686 270)
			(size 0.4318 0.4318)
			(layers "F.Cu" "F.Mask" "F.Paste")
			(net "GND")
		)
		(pad "AP85" smd circle
			(at 32.541718 -11.457686 270)
			(size 0.4318 0.4318)
			(layers "F.Cu" "F.Mask" "F.Paste")
			(net "P5E_CPU1_PE4_TX_DN<11>")
		)
		(pad "AP87" smd circle
			(at 34.169604 -11.457686 270)
			(size 0.4318 0.4318)
			(layers "F.Cu" "F.Mask" "F.Paste")
			(net "GND")
		)
		(pad "AP89" smd circle
			(at 35.797236 -11.457686 270)
			(size 0.4318 0.4318)
			(layers "F.Cu" "F.Mask" "F.Paste")
			(net "P5E_CPU1_PE4_RX_DN<11>")
		)
		(pad "AP91" smd oval
			(at 37.425122 -11.457686)
			(size 0.381 0.4826)
			(drill
				(offset 0 -0.0508)
			)
			(layers "F.Cu" "F.Mask" "F.Paste")
			(net "GND")
		)
		(pad "AR1" smd oval
			(at -37.425122 -11.097514 180)
			(size 0.381 0.4826)
			(drill
				(offset 0 -0.0508)
			)
			(layers "F.Cu" "F.Mask" "F.Paste")
			(net "GND")
		)
		(pad "AR3" smd circle
			(at -35.797236 -11.097514 270)
			(size 0.4318 0.4318)
			(layers "F.Cu" "F.Mask" "F.Paste")
			(net "UPI_CPU1_CPU0_P0P1_DP<13>")
		)
		(pad "AR5" smd circle
			(at -34.169604 -11.097514 270)
			(size 0.4318 0.4318)
			(layers "F.Cu" "F.Mask" "F.Paste")
			(net "GND")
		)
		(pad "AR7" smd circle
			(at -32.541718 -11.097514 270)
			(size 0.4318 0.4318)
			(layers "F.Cu" "F.Mask" "F.Paste")
			(net "UPI_CPU0_CPU1_P1P0_DP<12>")
		)
		(pad "AR9" smd circle
			(at -30.914086 -11.097514 270)
			(size 0.4318 0.4318)
			(layers "F.Cu" "F.Mask" "F.Paste")
			(net "GND")
		)
		(pad "AR11" smd circle
			(at -29.2862 -11.097514 270)
			(size 0.4318 0.4318)
			(layers "F.Cu" "F.Mask" "F.Paste")
			(net "P5E_CPU1_PE0_RX_DP<12>")
		)
		(pad "AR13" smd circle
			(at -27.658314 -11.097514 270)
			(size 0.4318 0.4318)
			(layers "F.Cu" "F.Mask" "F.Paste")
			(net "GND")
		)
		(pad "AR15" smd circle
			(at -26.030682 -11.097514 270)
			(size 0.4318 0.4318)
			(layers "F.Cu" "F.Mask" "F.Paste")
			(net "P5E_CPU1_PE0_TX_DP<11>")
		)
		(pad "AR17" smd circle
			(at -24.402796 -11.097514 270)
			(size 0.4318 0.4318)
			(layers "F.Cu" "F.Mask" "F.Paste")
			(net "NC_CPU1_UPI0_APROBE<1>")
		)
		(pad "AR19" smd circle
			(at -22.77491 -11.097514 270)
			(size 0.4318 0.4318)
			(layers "F.Cu" "F.Mask" "F.Paste")
			(net "GND")
		)
		(pad "AR21" smd circle
			(at -21.147278 -11.097514 270)
			(size 0.4318 0.4318)
			(layers "F.Cu" "F.Mask" "F.Paste")
			(net "M_D_CPU1_SB_DQS_DP<8>")
		)
		(pad "AR23" smd circle
			(at -19.519392 -11.097514 270)
			(size 0.4318 0.4318)
			(layers "F.Cu" "F.Mask" "F.Paste")
			(net "GND")
		)
		(pad "AR25" smd circle
			(at -17.89176 -11.097514 270)
			(size 0.4318 0.4318)
			(layers "F.Cu" "F.Mask" "F.Paste")
			(net "GND")
		)
		(pad "AR27" smd circle
			(at -16.263874 -11.097514 270)
			(size 0.4318 0.4318)
			(layers "F.Cu" "F.Mask" "F.Paste")
			(net "M_D_CPU1_SB_DQS_DP<6>")
		)
		(pad "AR29" smd circle
			(at -14.635988 -11.097514 270)
			(size 0.4318 0.4318)
			(layers "F.Cu" "F.Mask" "F.Paste")
			(net "GND")
		)
		(pad "AR31" smd circle
			(at -13.008356 -11.097514 270)
			(size 0.4318 0.4318)
			(layers "F.Cu" "F.Mask" "F.Paste")
			(net "GND")
		)
		(pad "AR33" smd circle
			(at -11.380724 -11.097514 270)
			(size 0.4318 0.4318)
			(layers "F.Cu" "F.Mask" "F.Paste")
			(net "M_D_CPU1_SB_DQS_DP<5>")
		)
		(pad "AR35" smd circle
			(at -9.752838 -11.097514 270)
			(size 0.4318 0.4318)
			(layers "F.Cu" "F.Mask" "F.Paste")
			(net "GND")
		)
		(pad "AR37" smd circle
			(at -8.124952 -11.097514 270)
			(size 0.4318 0.4318)
			(layers "F.Cu" "F.Mask" "F.Paste")
			(net "GND")
		)
		(pad "AR39" smd circle
			(at -6.49732 -11.097514 270)
			(size 0.4318 0.4318)
			(layers "F.Cu" "F.Mask" "F.Paste")
			(net "M_D_CPU1_SB_DQS_DN<4>")
		)
		(pad "AR41" smd circle
			(at -4.869434 -11.097514 270)
			(size 0.4318 0.4318)
			(layers "F.Cu" "F.Mask" "F.Paste")
			(net "GND")
		)
		(pad "AR43" smd circle
			(at -3.241802 -11.097514 270)
			(size 0.4318 0.4318)
			(layers "F.Cu" "F.Mask" "F.Paste")
			(net "GND")
		)
		(pad "AR45" smd circle
			(at -1.613916 -11.097514 270)
			(size 0.4318 0.4318)
			(layers "F.Cu" "F.Mask" "F.Paste")
			(net "M_D_CPU1_CLK_DP<1>")
		)
		(pad "AR48" smd circle
			(at 2.427732 -10.987532 270)
			(size 0.4318 0.4318)
			(layers "F.Cu" "F.Mask" "F.Paste")
			(net "GND")
		)
		(pad "AR50" smd circle
			(at 4.055618 -10.987532 270)
			(size 0.4318 0.4318)
			(layers "F.Cu" "F.Mask" "F.Paste")
			(net "GND")
		)
		(pad "AR52" smd circle
			(at 5.68325 -10.987532 270)
			(size 0.4318 0.4318)
			(layers "F.Cu" "F.Mask" "F.Paste")
			(net "M_D_CPU1_SA_CA<1>")
		)
		(pad "AR54" smd circle
			(at 7.311136 -10.987532 270)
			(size 0.4318 0.4318)
			(layers "F.Cu" "F.Mask" "F.Paste")
			(net "GND")
		)
		(pad "AR56" smd circle
			(at 8.939022 -10.987532 270)
			(size 0.4318 0.4318)
			(layers "F.Cu" "F.Mask" "F.Paste")
			(net "GND")
		)
		(pad "AR58" smd circle
			(at 10.566654 -10.987532 270)
			(size 0.4318 0.4318)
			(layers "F.Cu" "F.Mask" "F.Paste")
			(net "M_D_CPU1_SA_DQS_DP<9>")
		)
		(pad "AR60" smd circle
			(at 12.19454 -10.987532 270)
			(size 0.4318 0.4318)
			(layers "F.Cu" "F.Mask" "F.Paste")
			(net "GND")
		)
		(pad "AR62" smd circle
			(at 13.822426 -10.987532 270)
			(size 0.4318 0.4318)
			(layers "F.Cu" "F.Mask" "F.Paste")
			(net "GND")
		)
		(pad "AR64" smd circle
			(at 15.450058 -10.987532 270)
			(size 0.4318 0.4318)
			(layers "F.Cu" "F.Mask" "F.Paste")
			(net "M_D_CPU1_SA_DQS_DP<8>")
		)
		(pad "AR66" smd circle
			(at 17.07769 -10.987532 270)
			(size 0.4318 0.4318)
			(layers "F.Cu" "F.Mask" "F.Paste")
			(net "GND")
		)
		(pad "AR68" smd circle
			(at 18.705576 -10.987532 270)
			(size 0.4318 0.4318)
			(layers "F.Cu" "F.Mask" "F.Paste")
			(net "GND")
		)
		(pad "AR70" smd circle
			(at 20.333462 -10.987532 270)
			(size 0.4318 0.4318)
			(layers "F.Cu" "F.Mask" "F.Paste")
			(net "M_D_CPU1_SA_DQS_DP<7>")
		)
		(pad "AR72" smd circle
			(at 21.961094 -10.987532 270)
			(size 0.4318 0.4318)
			(layers "F.Cu" "F.Mask" "F.Paste")
			(net "GND")
		)
		(pad "AR74" smd circle
			(at 23.58898 -10.987532 270)
			(size 0.4318 0.4318)
			(layers "F.Cu" "F.Mask" "F.Paste")
			(net "GND")
		)
		(pad "AR76" smd circle
			(at 25.216612 -10.987532 270)
			(size 0.4318 0.4318)
			(layers "F.Cu" "F.Mask" "F.Paste")
			(net "M_D_CPU1_SA_DQS_DP<6>")
		)
		(pad "AR78" smd circle
			(at 26.844498 -10.987532 270)
			(size 0.4318 0.4318)
			(layers "F.Cu" "F.Mask" "F.Paste")
			(net "GND")
		)
		(pad "AR80" smd circle
			(at 28.472384 -10.987532 270)
			(size 0.4318 0.4318)
			(layers "F.Cu" "F.Mask" "F.Paste")
			(net "UPI_CPU1_CPU0_P2P2_DN<14>")
		)
		(pad "AR82" smd circle
			(at 30.100016 -10.987532 270)
			(size 0.4318 0.4318)
			(layers "F.Cu" "F.Mask" "F.Paste")
			(net "GND")
		)
		(pad "AR84" smd circle
			(at 31.727902 -10.987532 270)
			(size 0.4318 0.4318)
			(layers "F.Cu" "F.Mask" "F.Paste")
			(net "GND")
		)
		(pad "AR86" smd circle
			(at 33.355534 -10.987532 270)
			(size 0.4318 0.4318)
			(layers "F.Cu" "F.Mask" "F.Paste")
			(net "P5E_CPU1_PE4_TX_DN<12>")
		)
		(pad "AR88" smd circle
			(at 34.98342 -10.987532 270)
			(size 0.4318 0.4318)
			(layers "F.Cu" "F.Mask" "F.Paste")
			(net "GND")
		)
		(pad "AR90" smd circle
			(at 36.611306 -10.987532 270)
			(size 0.4318 0.4318)
			(layers "F.Cu" "F.Mask" "F.Paste")
			(net "P5E_CPU1_PE4_RX_DP<12>")
		)
		(pad "AT2" smd circle
			(at -36.611306 -10.627868 270)
			(size 0.4318 0.4318)
			(layers "F.Cu" "F.Mask" "F.Paste")
			(net "UPI_CPU1_CPU0_P0P1_DN<13>")
		)
		(pad "AT4" smd circle
			(at -34.98342 -10.627868 270)
			(size 0.4318 0.4318)
			(layers "F.Cu" "F.Mask" "F.Paste")
			(net "GND")
		)
		(pad "AT6" smd circle
			(at -33.355534 -10.627868 270)
			(size 0.4318 0.4318)
			(layers "F.Cu" "F.Mask" "F.Paste")
			(net "UPI_CPU0_CPU1_P1P0_DP<13>")
		)
		(pad "AT8" smd circle
			(at -31.727902 -10.627868 270)
			(size 0.4318 0.4318)
			(layers "F.Cu" "F.Mask" "F.Paste")
			(net "GND")
		)
		(pad "AT10" smd circle
			(at -30.100016 -10.627868 270)
			(size 0.4318 0.4318)
			(layers "F.Cu" "F.Mask" "F.Paste")
			(net "P5E_CPU1_PE0_RX_DP<13>")
		)
		(pad "AT12" smd circle
			(at -28.472384 -10.627868 270)
			(size 0.4318 0.4318)
			(layers "F.Cu" "F.Mask" "F.Paste")
			(net "GND")
		)
		(pad "AT14" smd circle
			(at -26.844498 -10.627868 270)
			(size 0.4318 0.4318)
			(layers "F.Cu" "F.Mask" "F.Paste")
			(net "P5E_CPU1_PE0_TX_DP<12>")
		)
		(pad "AT16" smd circle
			(at -25.216612 -10.627868 270)
			(size 0.4318 0.4318)
			(layers "F.Cu" "F.Mask" "F.Paste")
			(net "GND")
		)
		(pad "AT18" smd circle
			(at -23.58898 -10.627868 270)
			(size 0.4318 0.4318)
			(layers "F.Cu" "F.Mask" "F.Paste")
			(net "PD_CPU1_BIST_ENABLE")
		)
		(pad "AT20" smd circle
			(at -21.961094 -10.627868 270)
			(size 0.4318 0.4318)
			(layers "F.Cu" "F.Mask" "F.Paste")
			(net "GND")
		)
		(pad "AT22" smd circle
			(at -20.333462 -10.627868 270)
			(size 0.4318 0.4318)
			(layers "F.Cu" "F.Mask" "F.Paste")
			(net "GND")
		)
		(pad "AT24" smd circle
			(at -18.705576 -10.627868 270)
			(size 0.4318 0.4318)
			(layers "F.Cu" "F.Mask" "F.Paste")
			(net "CPU1_RSVD<4>")
		)
		(pad "AT26" smd circle
			(at -17.07769 -10.627868 270)
			(size 0.4318 0.4318)
			(layers "F.Cu" "F.Mask" "F.Paste")
			(net "GND")
		)
		(pad "AT28" smd circle
			(at -15.450058 -10.627868 270)
			(size 0.4318 0.4318)
			(layers "F.Cu" "F.Mask" "F.Paste")
			(net "GND")
		)
		(pad "AT30" smd circle
			(at -13.822426 -10.627868 270)
			(size 0.4318 0.4318)
			(layers "F.Cu" "F.Mask" "F.Paste")
			(net "CLK_100M_DB2000_CPU1_BCLK0_DN")
		)
		(pad "AT32" smd circle
			(at -12.19454 -10.627868 270)
			(size 0.4318 0.4318)
			(layers "F.Cu" "F.Mask" "F.Paste")
			(net "GND")
		)
		(pad "AT34" smd circle
			(at -10.566654 -10.627868 270)
			(size 0.4318 0.4318)
			(layers "F.Cu" "F.Mask" "F.Paste")
			(net "GND")
		)
		(pad "AT36" smd circle
			(at -8.939022 -10.627868 270)
			(size 0.4318 0.4318)
			(layers "F.Cu" "F.Mask" "F.Paste")
			(net "PVCCD_HV_CPU1")
		)
		(pad "AT38" smd circle
			(at -7.311136 -10.627868 270)
			(size 0.4318 0.4318)
			(layers "F.Cu" "F.Mask" "F.Paste")
			(net "GND")
		)
		(pad "AT40" smd circle
			(at -5.68325 -10.627868 270)
			(size 0.4318 0.4318)
			(layers "F.Cu" "F.Mask" "F.Paste")
			(net "GND")
		)
		(pad "AT42" smd circle
			(at -4.055618 -10.627868 270)
			(size 0.4318 0.4318)
			(layers "F.Cu" "F.Mask" "F.Paste")
			(net "M_A_CPU1_SA_RSP<0>")
		)
		(pad "AT44" smd circle
			(at -2.427732 -10.627868 270)
			(size 0.4318 0.4318)
			(layers "F.Cu" "F.Mask" "F.Paste")
			(net "GND")
		)
		(pad "AT47" smd circle
			(at 1.613916 -10.517886 270)
			(size 0.4318 0.4318)
			(layers "F.Cu" "F.Mask" "F.Paste")
			(net "M_C_CPU1_ALERT_N")
		)
		(pad "AT49" smd circle
			(at 3.241802 -10.517886 270)
			(size 0.4318 0.4318)
			(layers "F.Cu" "F.Mask" "F.Paste")
			(net "M_A_CPU1_ALERT_N")
		)
		(pad "AT51" smd circle
			(at 4.869434 -10.517886 270)
			(size 0.4318 0.4318)
			(layers "F.Cu" "F.Mask" "F.Paste")
			(net "GND")
		)
		(pad "AT53" smd circle
			(at 6.49732 -10.517886 270)
			(size 0.4318 0.4318)
			(layers "F.Cu" "F.Mask" "F.Paste")
			(net "GND")
		)
		(pad "AT55" smd circle
			(at 8.124952 -10.517886 270)
			(size 0.4318 0.4318)
			(layers "F.Cu" "F.Mask" "F.Paste")
			(net "PVCCD_HV_CPU1")
		)
		(pad "AT57" smd circle
			(at 9.752838 -10.517886 270)
			(size 0.4318 0.4318)
			(layers "F.Cu" "F.Mask" "F.Paste")
			(net "GND")
		)
		(pad "AT59" smd circle
			(at 11.380724 -10.517886 270)
			(size 0.4318 0.4318)
			(layers "F.Cu" "F.Mask" "F.Paste")
			(net "GND")
		)
		(pad "AT61" smd circle
			(at 13.008356 -10.517886 270)
			(size 0.4318 0.4318)
			(layers "F.Cu" "F.Mask" "F.Paste")
			(net "PVCCFA_EHV_CPU1")
		)
		(pad "AT63" smd circle
			(at 14.635988 -10.517886 270)
			(size 0.4318 0.4318)
			(layers "F.Cu" "F.Mask" "F.Paste")
			(net "GND")
		)
		(pad "AT65" smd circle
			(at 16.263874 -10.517886 270)
			(size 0.4318 0.4318)
			(layers "F.Cu" "F.Mask" "F.Paste")
			(net "GND")
		)
		(pad "AT67" smd circle
			(at 17.89176 -10.517886 270)
			(size 0.4318 0.4318)
			(layers "F.Cu" "F.Mask" "F.Paste")
			(net "NC_CPU1_UPI2_APROBE<1>")
		)
		(pad "AT69" smd circle
			(at 19.519392 -10.517886 270)
			(size 0.4318 0.4318)
			(layers "F.Cu" "F.Mask" "F.Paste")
			(net "GND")
		)
		(pad "AT71" smd circle
			(at 21.147278 -10.517886 270)
			(size 0.4318 0.4318)
			(layers "F.Cu" "F.Mask" "F.Paste")
			(net "GND")
		)
		(pad "AT73" smd circle
			(at 22.77491 -10.517886 270)
			(size 0.4318 0.4318)
			(layers "F.Cu" "F.Mask" "F.Paste")
			(net "PVCCFA_EHV_FIVRA_CPU1")
		)
		(pad "AT75" smd circle
			(at 24.402796 -10.517886 270)
			(size 0.4318 0.4318)
			(layers "F.Cu" "F.Mask" "F.Paste")
			(net "GND")
		)
		(pad "AT77" smd circle
			(at 26.030682 -10.517886 270)
			(size 0.4318 0.4318)
			(layers "F.Cu" "F.Mask" "F.Paste")
			(net "GND")
		)
		(pad "AT79" smd circle
			(at 27.658314 -10.517886 270)
			(size 0.4318 0.4318)
			(layers "F.Cu" "F.Mask" "F.Paste")
			(net "GND")
		)
		(pad "AT81" smd circle
			(at 29.2862 -10.517886 270)
			(size 0.4318 0.4318)
			(layers "F.Cu" "F.Mask" "F.Paste")
			(net "UPI_CPU1_CPU0_P2P2_DP<14>")
		)
		(pad "AT83" smd circle
			(at 30.914086 -10.517886 270)
			(size 0.4318 0.4318)
			(layers "F.Cu" "F.Mask" "F.Paste")
			(net "UPI_CPU1_CPU0_P2P2_DN<15>")
		)
		(pad "AT85" smd circle
			(at 32.541718 -10.517886 270)
			(size 0.4318 0.4318)
			(layers "F.Cu" "F.Mask" "F.Paste")
			(net "VSENSE_PVCCFA_EHV_FIVRA_CPU1_DN")
		)
		(pad "AT87" smd circle
			(at 34.169604 -10.517886 270)
			(size 0.4318 0.4318)
			(layers "F.Cu" "F.Mask" "F.Paste")
			(net "P5E_CPU1_PE4_TX_DP<12>")
		)
		(pad "AT89" smd circle
			(at 35.797236 -10.517886 270)
			(size 0.4318 0.4318)
			(layers "F.Cu" "F.Mask" "F.Paste")
			(net "PVCCFA_EHV_FIVRA_CPU1")
		)
		(pad "AT91" smd oval
			(at 37.425122 -10.517886)
			(size 0.381 0.4826)
			(drill
				(offset 0 -0.0508)
			)
			(layers "F.Cu" "F.Mask" "F.Paste")
			(net "P5E_CPU1_PE4_RX_DN<12>")
		)
		(pad "AU1" smd oval
			(at -37.425122 -10.157714 180)
			(size 0.381 0.4826)
			(drill
				(offset 0 -0.0508)
			)
			(layers "F.Cu" "F.Mask" "F.Paste")
			(net "UPI_CPU1_CPU0_P0P1_DN<14>")
		)
		(pad "AU3" smd circle
			(at -35.797236 -10.157714 270)
			(size 0.4318 0.4318)
			(layers "F.Cu" "F.Mask" "F.Paste")
			(net "PVCCD_HV_CPU1")
		)
		(pad "AU5" smd circle
			(at -34.169604 -10.157714 270)
			(size 0.4318 0.4318)
			(layers "F.Cu" "F.Mask" "F.Paste")
			(net "UPI_CPU0_CPU1_P1P0_DN<13>")
		)
	)
)
